# T6G (Grand Teton) — schematic netlist excerpt (pin names and nets, part order shuffled) for the footprints in the layout excerpt that follows; sources: Cadence DE-HDL packaged netlist, KiCad conversion of 04192023_DAF0TMB3IC0_F0TG_MB_C_brd_V02_OCP.brd

C1563  Q_CAP  0.1UF 16V 10% X7R  pkg C0402  page 187 : A = CLR_CMOS ; B = GND
C2528  Q_CAP  22UF 4V 20% X6S  pkg C0402  page 70 : A = PVDDCR_SOC_P0 ; B = GND

(kicad_pcb
	(version 20260206)
	(generator "pcbnew")
	(generator_version "10.0")
	(general
		(thickness 1.6)
		(legacy_teardrops no)
	)
	(paper "A4")
	(title_block
		(title "04192023_DAF0TMB3IC0_F0TG_MB_C_brd_V02_OCP.brd")
		(comment 1 "Grand Teton / footprints 2596-2597 of 8354")
	)
	(layers
		(0 "F.Cu" signal "TOP")
		(4 "In1.Cu" signal "GND")
		(6 "In2.Cu" signal "IN1")
		(8 "In3.Cu" signal "GND1")
		(10 "In4.Cu" signal "IN2")
		(12 "In5.Cu" signal "GND2")
		(14 "In6.Cu" signal "IN3")
		(16 "In7.Cu" signal "GND3")
		(18 "In8.Cu" signal "VCC")
		(20 "In9.Cu" signal "VCC1")
		(22 "In10.Cu" signal "GND4")
		(24 "In11.Cu" signal "IN4")
		(26 "In12.Cu" signal "GND5")
		(28 "In13.Cu" signal "IN5")
		(30 "In14.Cu" signal "GND6")
		(32 "In15.Cu" signal "IN6")
		(34 "In16.Cu" signal "GND7")
		(2 "B.Cu" signal "BOTTOM")
		(9 "F.Adhes" user "F.Adhesive")
		(11 "B.Adhes" user "B.Adhesive")
		(13 "F.Paste" user "Package Geometry/Pastemask Top")
		(15 "B.Paste" user "Package Geometry/Pastemask Bottom")
		(5 "F.SilkS" user "Ref Des/Silkscreen Top")
		(7 "B.SilkS" user "Ref Des/Silkscreen Bottom")
		(1 "F.Mask" user "Board Geometry/Soldermask Top")
		(3 "B.Mask" user "Board Geometry/Soldermask Bottom")
		(17 "Dwgs.User" user "User.Drawings")
		(19 "Cmts.User" user "User.Comments")
		(21 "Eco1.User" user "User.Eco1")
		(23 "Eco2.User" user "User.Eco2")
		(25 "Edge.Cuts" user "Board Geometry/Outline")
		(27 "Margin" user)
		(31 "F.CrtYd" user "Package Geometry/Place Bound Top")
		(29 "B.CrtYd" user "Package Geometry/Place Bound Bottom")
		(35 "F.Fab" user "Ref Des/Assembly Top")
		(33 "B.Fab" user "Ref Des/Assembly Bottom")
	)
	(footprint ""
		(layer "F.Cu")
		(at 364.165896 -256.012188 90)
		(property "Reference" "C2528"
			(at 0 0 90)
			(layer "F.SilkS")
			(hide yes)
			(effects
				(font
					(size 1.27 1.27)
				)
			)
		)
		(property "Value" ""
			(at 0 0 90)
			(layer "F.Fab")
			(effects
				(font
					(size 1.27 1.27)
				)
			)
		)
		(duplicate_pad_numbers_are_jumpers no)
		(fp_line
			(start 0.7874 -0.4064)
			(end 0.7874 0.4064)
			(stroke
				(width 0.1524)
				(type default)
			)
			(layer "F.SilkS")
		)
		(fp_line
			(start -0.7874 -0.4064)
			(end 0.7874 -0.4064)
			(stroke
				(width 0.1524)
				(type default)
			)
			(layer "F.SilkS")
		)
		(fp_line
			(start 0.7874 0.4064)
			(end -0.7874 0.4064)
			(stroke
				(width 0.1524)
				(type default)
			)
			(layer "F.SilkS")
		)
		(fp_line
			(start -0.7874 0.4064)
			(end -0.7874 -0.4064)
			(stroke
				(width 0.1524)
				(type default)
			)
			(layer "F.SilkS")
		)
		(fp_line
			(start -0.12065 -0.305054)
			(end -0.12065 -0.2794)
			(stroke
				(width 0.1)
				(type default)
			)
			(layer "F.Fab")
		)
		(fp_line
			(start -0.67945 -0.305054)
			(end -0.12065 -0.305054)
			(stroke
				(width 0.1)
				(type default)
			)
			(layer "F.Fab")
		)
		(fp_line
			(start 0.67945 -0.3048)
			(end 0.67945 0.3048)
			(stroke
				(width 0.1)
				(type default)
			)
			(layer "F.Fab")
		)
		(fp_line
			(start 0.12065 -0.3048)
			(end 0.67945 -0.3048)
			(stroke
				(width 0.1)
				(type default)
			)
			(layer "F.Fab")
		)
		(fp_line
			(start 0.12065 -0.2794)
			(end 0.12065 -0.3048)
			(stroke
				(width 0.1)
				(type default)
			)
			(layer "F.Fab")
		)
		(fp_line
			(start -0.12065 -0.2794)
			(end 0.12065 -0.2794)
			(stroke
				(width 0.1)
				(type default)
			)
			(layer "F.Fab")
		)
		(fp_line
			(start 0.120396 0.2794)
			(end -0.12065 0.2794)
			(stroke
				(width 0.1)
				(type default)
			)
			(layer "F.Fab")
		)
		(fp_line
			(start -0.12065 0.2794)
			(end -0.12065 0.3048)
			(stroke
				(width 0.1)
				(type default)
			)
			(layer "F.Fab")
		)
		(fp_line
			(start 0.67945 0.3048)
			(end 0.120396 0.3048)
			(stroke
				(width 0.1)
				(type default)
			)
			(layer "F.Fab")
		)
		(fp_line
			(start 0.120396 0.3048)
			(end 0.120396 0.2794)
			(stroke
				(width 0.1)
				(type default)
			)
			(layer "F.Fab")
		)
		(fp_line
			(start -0.12065 0.3048)
			(end -0.67945 0.3048)
			(stroke
				(width 0.1)
				(type default)
			)
			(layer "F.Fab")
		)
		(fp_line
			(start -0.67945 0.3048)
			(end -0.67945 -0.305054)
			(stroke
				(width 0.1)
				(type default)
			)
			(layer "F.Fab")
		)
		(pad "1" smd circle
			(at -0.40005 0 90)
			(size 0 0)
			(layers "F.Cu" "F.Mask" "F.Paste")
			(net "PVDDCR_SOC_P0")
		)
		(pad "2" smd circle
			(at 0.40005 0 90)
			(size 0 0)
			(layers "F.Cu" "F.Mask" "F.Paste")
			(net "GND")
		)
	)
	(footprint ""
		(layer "F.Cu")
		(at 301.621952 -22.12975)
		(property "Reference" "C1563"
			(at 0 0 0)
			(layer "F.SilkS")
			(hide yes)
			(effects
				(font
					(size 1.27 1.27)
				)
			)
		)
		(property "Value" ""
			(at 0 0 0)
			(layer "F.Fab")
			(effects
				(font
					(size 1.27 1.27)
				)
			)
		)
		(duplicate_pad_numbers_are_jumpers no)
		(fp_line
			(start -0.7874 -0.4064)
			(end 0.7874 -0.4064)
			(stroke
				(width 0.1524)
				(type default)
			)
			(layer "F.SilkS")
		)
		(fp_line
			(start -0.7874 0.4064)
			(end -0.7874 -0.4064)
			(stroke
				(width 0.1524)
				(type default)
			)
			(layer "F.SilkS")
		)
		(fp_line
			(start 0.7874 -0.4064)
			(end 0.7874 0.4064)
			(stroke
				(width 0.1524)
				(type default)
			)
			(layer "F.SilkS")
		)
		(fp_line
			(start 0.7874 0.4064)
			(end -0.7874 0.4064)
			(stroke
				(width 0.1524)
				(type default)
			)
			(layer "F.SilkS")
		)
		(fp_line
			(start -0.67945 -0.305054)
			(end -0.12065 -0.305054)
			(stroke
				(width 0.1)
				(type default)
			)
			(layer "F.Fab")
		)
		(fp_line
			(start -0.67945 0.3048)
			(end -0.67945 -0.305054)
			(stroke
				(width 0.1)
				(type default)
			)
			(layer "F.Fab")
		)
		(fp_line
			(start -0.12065 -0.305054)
			(end -0.12065 -0.2794)
			(stroke
				(width 0.1)
				(type default)
			)
			(layer "F.Fab")
		)
		(fp_line
			(start -0.12065 -0.2794)
			(end 0.12065 -0.2794)
			(stroke
				(width 0.1)
				(type default)
			)
			(layer "F.Fab")
		)
		(fp_line
			(start -0.12065 0.2794)
			(end -0.12065 0.3048)
			(stroke
				(width 0.1)
				(type default)
			)
			(layer "F.Fab")
		)
		(fp_line
			(start -0.12065 0.3048)
			(end -0.67945 0.3048)
			(stroke
				(width 0.1)
				(type default)
			)
			(layer "F.Fab")
		)
		(fp_line
			(start 0.120396 0.2794)
			(end -0.12065 0.2794)
			(stroke
				(width 0.1)
				(type default)
			)
			(layer "F.Fab")
		)
		(fp_line
			(start 0.120396 0.3048)
			(end 0.120396 0.2794)
			(stroke
				(width 0.1)
				(type default)
			)
			(layer "F.Fab")
		)
		(fp_line
			(start 0.12065 -0.3048)
			(end 0.67945 -0.3048)
			(stroke
				(width 0.1)
				(type default)
			)
			(layer "F.Fab")
		)
		(fp_line
			(start 0.12065 -0.2794)
			(end 0.12065 -0.3048)
			(stroke
				(width 0.1)
				(type default)
			)
			(layer "F.Fab")
		)
		(fp_line
			(start 0.67945 -0.3048)
			(end 0.67945 0.3048)
			(stroke
				(width 0.1)
				(type default)
			)
			(layer "F.Fab")
		)
		(fp_line
			(start 0.67945 0.3048)
			(end 0.120396 0.3048)
			(stroke
				(width 0.1)
				(type default)
			)
			(layer "F.Fab")
		)
		(pad "1" smd circle
			(at -0.40005 0)
			(size 0 0)
			(layers "F.Cu" "F.Mask" "F.Paste")
			(net "CLR_CMOS")
		)
		(pad "2" smd circle
			(at 0.40005 0)
			(size 0 0)
			(layers "F.Cu" "F.Mask" "F.Paste")
			(net "GND")
		)
	)
)
